(kicad_pcb
	(version 20260206)
	(generator "pcbnew")
	(generator_version "10.0")
	(general
		(thickness 1.6)
		(legacy_teardrops no)
	)
	(paper "A4")
	(title_block
		(title "01162023_DA0F0TEBIF0_F0T_Expander_BD_F_brd_V02_OCP.brd")
		(comment 1 "Grand Teton / footprints 1067-1073 of 9728")
	)
	(layers
		(0 "F.Cu" signal "TOP")
		(4 "In1.Cu" signal "GND")
		(6 "In2.Cu" signal "VCC")
		(8 "In3.Cu" signal "VCC1")
		(10 "In4.Cu" signal "GND1")
		(12 "In5.Cu" signal "IN1")
		(14 "In6.Cu" signal "GND2")
		(16 "In7.Cu" signal "IN2")
		(18 "In8.Cu" signal "GND3")
		(20 "In9.Cu" signal "IN3")
		(22 "In10.Cu" signal "GND4")
		(24 "In11.Cu" signal "IN4")
		(26 "In12.Cu" signal "GND5")
		(28 "In13.Cu" signal "IN5")
		(30 "In14.Cu" signal "GND6")
		(32 "In15.Cu" signal "IN6")
		(34 "In16.Cu" signal "GND7")
		(2 "B.Cu" signal "BOTTOM")
		(9 "F.Adhes" user "F.Adhesive")
		(11 "B.Adhes" user "B.Adhesive")
		(13 "F.Paste" user "Package Geometry/Pastemask Top")
		(15 "B.Paste" user "Package Geometry/Pastemask Bottom")
		(5 "F.SilkS" user "Ref Des/Silkscreen Top")
		(7 "B.SilkS" user "Ref Des/Silkscreen Bottom")
		(1 "F.Mask" user "Board Geometry/Soldermask Top")
		(3 "B.Mask" user "Board Geometry/Soldermask Bottom")
		(17 "Dwgs.User" user "User.Drawings")
		(19 "Cmts.User" user "User.Comments")
		(21 "Eco1.User" user "User.Eco1")
		(23 "Eco2.User" user "User.Eco2")
		(25 "Edge.Cuts" user "Board Geometry/Outline")
		(27 "Margin" user)
		(31 "F.CrtYd" user "Package Geometry/Place Bound Top")
		(29 "B.CrtYd" user "Package Geometry/Place Bound Bottom")
		(35 "F.Fab" user "Ref Des/Assembly Top")
		(33 "B.Fab" user "Ref Des/Assembly Bottom")
	)
	(footprint ""
		(layer "F.Cu")
		(at 336.466942 -57.332626)
		(property "Reference" "R6830"
			(at 0 0 0)
			(layer "F.SilkS")
			(hide yes)
			(effects
				(font
					(size 1.27 1.27)
				)
			)
		)
		(property "Value" ""
			(at 0 0 0)
			(layer "F.Fab")
			(effects
				(font
					(size 1.27 1.27)
				)
			)
		)
		(duplicate_pad_numbers_are_jumpers no)
		(fp_line
			(start -0.7874 -0.4064)
			(end 0.7874 -0.4064)
			(stroke
				(width 0.1524)
				(type default)
			)
			(layer "F.SilkS")
		)
		(fp_line
			(start -0.7874 0.4064)
			(end -0.7874 -0.4064)
			(stroke
				(width 0.1524)
				(type default)
			)
			(layer "F.SilkS")
		)
		(fp_line
			(start 0.7874 -0.4064)
			(end 0.7874 0.4064)
			(stroke
				(width 0.1524)
				(type default)
			)
			(layer "F.SilkS")
		)
		(fp_line
			(start 0.7874 0.4064)
			(end -0.7874 0.4064)
			(stroke
				(width 0.1524)
				(type default)
			)
			(layer "F.SilkS")
		)
		(fp_line
			(start -0.67945 -0.305054)
			(end -0.12065 -0.305054)
			(stroke
				(width 0.1)
				(type default)
			)
			(layer "F.Fab")
		)
		(fp_line
			(start -0.67945 0.3048)
			(end -0.67945 -0.305054)
			(stroke
				(width 0.1)
				(type default)
			)
			(layer "F.Fab")
		)
		(fp_line
			(start -0.12065 -0.305054)
			(end -0.12065 -0.2794)
			(stroke
				(width 0.1)
				(type default)
			)
			(layer "F.Fab")
		)
		(fp_line
			(start -0.12065 -0.2794)
			(end 0.12065 -0.2794)
			(stroke
				(width 0.1)
				(type default)
			)
			(layer "F.Fab")
		)
		(fp_line
			(start -0.12065 0.2794)
			(end -0.12065 0.3048)
			(stroke
				(width 0.1)
				(type default)
			)
			(layer "F.Fab")
		)
		(fp_line
			(start -0.12065 0.3048)
			(end -0.67945 0.3048)
			(stroke
				(width 0.1)
				(type default)
			)
			(layer "F.Fab")
		)
		(fp_line
			(start 0.120396 0.2794)
			(end -0.12065 0.2794)
			(stroke
				(width 0.1)
				(type default)
			)
			(layer "F.Fab")
		)
		(fp_line
			(start 0.120396 0.3048)
			(end 0.120396 0.2794)
			(stroke
				(width 0.1)
				(type default)
			)
			(layer "F.Fab")
		)
		(fp_line
			(start 0.12065 -0.3048)
			(end 0.67945 -0.3048)
			(stroke
				(width 0.1)
				(type default)
			)
			(layer "F.Fab")
		)
		(fp_line
			(start 0.12065 -0.2794)
			(end 0.12065 -0.3048)
			(stroke
				(width 0.1)
				(type default)
			)
			(layer "F.Fab")
		)
		(fp_line
			(start 0.67945 -0.3048)
			(end 0.67945 0.3048)
			(stroke
				(width 0.1)
				(type default)
			)
			(layer "F.Fab")
		)
		(fp_line
			(start 0.67945 0.3048)
			(end 0.120396 0.3048)
			(stroke
				(width 0.1)
				(type default)
			)
			(layer "F.Fab")
		)
		(pad "1" smd circle
			(at -0.40005 0)
			(size 0 0)
			(layers "F.Cu" "F.Mask" "F.Paste")
			(net "SSD11_PWR_EN_R")
		)
		(pad "2" smd circle
			(at 0.40005 0)
			(size 0 0)
			(layers "F.Cu" "F.Mask" "F.Paste")
			(net "GND")
		)
	)
	(footprint ""
		(layer "F.Cu")
		(at 123.67514 -96.034606)
		(property "Reference" "R1577"
			(at 0 0 0)
			(layer "F.SilkS")
			(hide yes)
			(effects
				(font
					(size 1.27 1.27)
				)
			)
		)
		(property "Value" ""
			(at 0 0 0)
			(layer "F.Fab")
			(effects
				(font
					(size 1.27 1.27)
				)
			)
		)
		(duplicate_pad_numbers_are_jumpers no)
		(fp_line
			(start -0.7874 -0.4064)
			(end 0.7874 -0.4064)
			(stroke
				(width 0.1524)
				(type default)
			)
			(layer "F.SilkS")
		)
		(fp_line
			(start -0.7874 0.4064)
			(end -0.7874 -0.4064)
			(stroke
				(width 0.1524)
				(type default)
			)
			(layer "F.SilkS")
		)
		(fp_line
			(start 0.7874 -0.4064)
			(end 0.7874 0.4064)
			(stroke
				(width 0.1524)
				(type default)
			)
			(layer "F.SilkS")
		)
		(fp_line
			(start 0.7874 0.4064)
			(end -0.7874 0.4064)
			(stroke
				(width 0.1524)
				(type default)
			)
			(layer "F.SilkS")
		)
		(fp_line
			(start -0.67945 -0.305054)
			(end -0.12065 -0.305054)
			(stroke
				(width 0.1)
				(type default)
			)
			(layer "F.Fab")
		)
		(fp_line
			(start -0.67945 0.3048)
			(end -0.67945 -0.305054)
			(stroke
				(width 0.1)
				(type default)
			)
			(layer "F.Fab")
		)
		(fp_line
			(start -0.12065 -0.305054)
			(end -0.12065 -0.2794)
			(stroke
				(width 0.1)
				(type default)
			)
			(layer "F.Fab")
		)
		(fp_line
			(start -0.12065 -0.2794)
			(end 0.12065 -0.2794)
			(stroke
				(width 0.1)
				(type default)
			)
			(layer "F.Fab")
		)
		(fp_line
			(start -0.12065 0.2794)
			(end -0.12065 0.3048)
			(stroke
				(width 0.1)
				(type default)
			)
			(layer "F.Fab")
		)
		(fp_line
			(start -0.12065 0.3048)
			(end -0.67945 0.3048)
			(stroke
				(width 0.1)
				(type default)
			)
			(layer "F.Fab")
		)
		(fp_line
			(start 0.120396 0.2794)
			(end -0.12065 0.2794)
			(stroke
				(width 0.1)
				(type default)
			)
			(layer "F.Fab")
		)
		(fp_line
			(start 0.120396 0.3048)
			(end 0.120396 0.2794)
			(stroke
				(width 0.1)
				(type default)
			)
			(layer "F.Fab")
		)
		(fp_line
			(start 0.12065 -0.3048)
			(end 0.67945 -0.3048)
			(stroke
				(width 0.1)
				(type default)
			)
			(layer "F.Fab")
		)
		(fp_line
			(start 0.12065 -0.2794)
			(end 0.12065 -0.3048)
			(stroke
				(width 0.1)
				(type default)
			)
			(layer "F.Fab")
		)
		(fp_line
			(start 0.67945 -0.3048)
			(end 0.67945 0.3048)
			(stroke
				(width 0.1)
				(type default)
			)
			(layer "F.Fab")
		)
		(fp_line
			(start 0.67945 0.3048)
			(end 0.120396 0.3048)
			(stroke
				(width 0.1)
				(type default)
			)
			(layer "F.Fab")
		)
		(pad "1" smd circle
			(at -0.40005 0)
			(size 0 0)
			(layers "F.Cu" "F.Mask" "F.Paste")
			(net "SMB_BIC_I2C9_MUX0_SSD0_R_SCL")
		)
		(pad "2" smd circle
			(at 0.40005 0)
			(size 0 0)
			(layers "F.Cu" "F.Mask" "F.Paste")
			(net "SMB_BIC_I2C9_MUX0_SSD0_SCL")
		)
	)
	(footprint ""
		(layer "F.Cu")
		(at 356.551738 -398.044924 90)
		(property "Reference" "C4456"
			(at 0 0 90)
			(layer "F.SilkS")
			(hide yes)
			(effects
				(font
					(size 1.27 1.27)
				)
			)
		)
		(property "Value" ""
			(at 0 0 90)
			(layer "F.Fab")
			(effects
				(font
					(size 1.27 1.27)
				)
			)
		)
		(duplicate_pad_numbers_are_jumpers no)
		(fp_line
			(start 0.299974 -0.150114)
			(end 0.299974 0.150114)
			(stroke
				(width 0.1)
				(type default)
			)
			(layer "F.Fab")
		)
		(fp_line
			(start -0.299974 -0.150114)
			(end 0.299974 -0.150114)
			(stroke
				(width 0.1)
				(type default)
			)
			(layer "F.Fab")
		)
		(fp_line
			(start 0.299974 0.150114)
			(end -0.299974 0.150114)
			(stroke
				(width 0.1)
				(type default)
			)
			(layer "F.Fab")
		)
		(fp_line
			(start -0.299974 0.150114)
			(end -0.299974 -0.150114)
			(stroke
				(width 0.1)
				(type default)
			)
			(layer "F.Fab")
		)
		(pad "1" smd rect
			(at -0.2667 0 90)
			(size 0.3048 0.381)
			(layers "F.Cu" "F.Mask" "F.Paste")
			(net "MB_3V3IO_RSVD3_ISO")
		)
		(pad "2" smd rect
			(at 0.2667 0 90)
			(size 0.3048 0.381)
			(layers "F.Cu" "F.Mask" "F.Paste")
			(net "GND")
		)
	)
	(footprint ""
		(layer "F.Cu")
		(at 45.093128 -356.244906 90)
		(property "Reference" "C2177"
			(at 0 0 90)
			(layer "F.SilkS")
			(hide yes)
			(effects
				(font
					(size 1.27 1.27)
				)
			)
		)
		(property "Value" ""
			(at 0 0 90)
			(layer "F.Fab")
			(effects
				(font
					(size 1.27 1.27)
				)
			)
		)
		(duplicate_pad_numbers_are_jumpers no)
		(fp_line
			(start 0.299974 -0.150114)
			(end 0.299974 0.150114)
			(stroke
				(width 0.1)
				(type default)
			)
			(layer "F.Fab")
		)
		(fp_line
			(start -0.299974 -0.150114)
			(end 0.299974 -0.150114)
			(stroke
				(width 0.1)
				(type default)
			)
			(layer "F.Fab")
		)
		(fp_line
			(start 0.299974 0.150114)
			(end -0.299974 0.150114)
			(stroke
				(width 0.1)
				(type default)
			)
			(layer "F.Fab")
		)
		(fp_line
			(start -0.299974 0.150114)
			(end -0.299974 -0.150114)
			(stroke
				(width 0.1)
				(type default)
			)
			(layer "F.Fab")
		)
		(pad "1" smd rect
			(at -0.2667 0 90)
			(size 0.3048 0.381)
			(layers "F.Cu" "F.Mask" "F.Paste")
			(net "P5E_PEX0_STN4_TX_DN<67>")
		)
		(pad "2" smd rect
			(at 0.2667 0 90)
			(size 0.3048 0.381)
			(layers "F.Cu" "F.Mask" "F.Paste")
			(net "P5E_PEX0_STN4_TX_C_DN<67>")
		)
	)
	(footprint ""
		(layer "F.Cu")
		(at 190.12789 -35.876738)
		(property "Reference" "R6071"
			(at 0 0 0)
			(layer "F.SilkS")
			(hide yes)
			(effects
				(font
					(size 1.27 1.27)
				)
			)
		)
		(property "Value" ""
			(at 0 0 0)
			(layer "F.Fab")
			(effects
				(font
					(size 1.27 1.27)
				)
			)
		)
		(duplicate_pad_numbers_are_jumpers no)
		(fp_line
			(start -0.7874 -0.4064)
			(end 0.7874 -0.4064)
			(stroke
				(width 0.1524)
				(type default)
			)
			(layer "F.SilkS")
		)
		(fp_line
			(start -0.7874 0.4064)
			(end -0.7874 -0.4064)
			(stroke
				(width 0.1524)
				(type default)
			)
			(layer "F.SilkS")
		)
		(fp_line
			(start 0.7874 -0.4064)
			(end 0.7874 0.4064)
			(stroke
				(width 0.1524)
				(type default)
			)
			(layer "F.SilkS")
		)
		(fp_line
			(start 0.7874 0.4064)
			(end -0.7874 0.4064)
			(stroke
				(width 0.1524)
				(type default)
			)
			(layer "F.SilkS")
		)
		(fp_line
			(start -0.67945 -0.305054)
			(end -0.12065 -0.305054)
			(stroke
				(width 0.1)
				(type default)
			)
			(layer "F.Fab")
		)
		(fp_line
			(start -0.67945 0.3048)
			(end -0.67945 -0.305054)
			(stroke
				(width 0.1)
				(type default)
			)
			(layer "F.Fab")
		)
		(fp_line
			(start -0.12065 -0.305054)
			(end -0.12065 -0.2794)
			(stroke
				(width 0.1)
				(type default)
			)
			(layer "F.Fab")
		)
		(fp_line
			(start -0.12065 -0.2794)
			(end 0.12065 -0.2794)
			(stroke
				(width 0.1)
				(type default)
			)
			(layer "F.Fab")
		)
		(fp_line
			(start -0.12065 0.2794)
			(end -0.12065 0.3048)
			(stroke
				(width 0.1)
				(type default)
			)
			(layer "F.Fab")
		)
		(fp_line
			(start -0.12065 0.3048)
			(end -0.67945 0.3048)
			(stroke
				(width 0.1)
				(type default)
			)
			(layer "F.Fab")
		)
		(fp_line
			(start 0.120396 0.2794)
			(end -0.12065 0.2794)
			(stroke
				(width 0.1)
				(type default)
			)
			(layer "F.Fab")
		)
		(fp_line
			(start 0.120396 0.3048)
			(end 0.120396 0.2794)
			(stroke
				(width 0.1)
				(type default)
			)
			(layer "F.Fab")
		)
		(fp_line
			(start 0.12065 -0.3048)
			(end 0.67945 -0.3048)
			(stroke
				(width 0.1)
				(type default)
			)
			(layer "F.Fab")
		)
		(fp_line
			(start 0.12065 -0.2794)
			(end 0.12065 -0.3048)
			(stroke
				(width 0.1)
				(type default)
			)
			(layer "F.Fab")
		)
		(fp_line
			(start 0.67945 -0.3048)
			(end 0.67945 0.3048)
			(stroke
				(width 0.1)
				(type default)
			)
			(layer "F.Fab")
		)
		(fp_line
			(start 0.67945 0.3048)
			(end 0.120396 0.3048)
			(stroke
				(width 0.1)
				(type default)
			)
			(layer "F.Fab")
		)
		(pad "1" smd circle
			(at -0.40005 0)
			(size 0 0)
			(layers "F.Cu" "F.Mask" "F.Paste")
			(net "PWRGD_P3V3_SSD7_D")
		)
		(pad "2" smd circle
			(at 0.40005 0)
			(size 0 0)
			(layers "F.Cu" "F.Mask" "F.Paste")
			(net "PWRGD_P3V3_SSD7_R")
		)
	)
	(footprint ""
		(layer "F.Cu")
		(at 339.598 -205.232 -90)
		(property "Reference" "R4132"
			(at 0 0 270)
			(layer "F.SilkS")
			(hide yes)
			(effects
				(font
					(size 1.27 1.27)
				)
			)
		)
		(property "Value" ""
			(at 0 0 270)
			(layer "F.Fab")
			(effects
				(font
					(size 1.27 1.27)
				)
			)
		)
		(duplicate_pad_numbers_are_jumpers no)
		(fp_line
			(start -0.7874 0.4064)
			(end -0.7874 -0.4064)
			(stroke
				(width 0.1524)
				(type default)
			)
			(layer "F.SilkS")
		)
		(fp_line
			(start 0.7874 0.4064)
			(end -0.7874 0.4064)
			(stroke
				(width 0.1524)
				(type default)
			)
			(layer "F.SilkS")
		)
		(fp_line
			(start -0.7874 -0.4064)
			(end 0.7874 -0.4064)
			(stroke
				(width 0.1524)
				(type default)
			)
			(layer "F.SilkS")
		)
		(fp_line
			(start 0.7874 -0.4064)
			(end 0.7874 0.4064)
			(stroke
				(width 0.1524)
				(type default)
			)
			(layer "F.SilkS")
		)
		(fp_line
			(start -0.67945 0.3048)
			(end -0.67945 -0.305054)
			(stroke
				(width 0.1)
				(type default)
			)
			(layer "F.Fab")
		)
		(fp_line
			(start -0.12065 0.3048)
			(end -0.67945 0.3048)
			(stroke
				(width 0.1)
				(type default)
			)
			(layer "F.Fab")
		)
		(fp_line
			(start 0.120396 0.3048)
			(end 0.120396 0.2794)
			(stroke
				(width 0.1)
				(type default)
			)
			(layer "F.Fab")
		)
		(fp_line
			(start 0.67945 0.3048)
			(end 0.120396 0.3048)
			(stroke
				(width 0.1)
				(type default)
			)
			(layer "F.Fab")
		)
		(fp_line
			(start -0.12065 0.2794)
			(end -0.12065 0.3048)
			(stroke
				(width 0.1)
				(type default)
			)
			(layer "F.Fab")
		)
		(fp_line
			(start 0.120396 0.2794)
			(end -0.12065 0.2794)
			(stroke
				(width 0.1)
				(type default)
			)
			(layer "F.Fab")
		)
		(fp_line
			(start -0.12065 -0.2794)
			(end 0.12065 -0.2794)
			(stroke
				(width 0.1)
				(type default)
			)
			(layer "F.Fab")
		)
		(fp_line
			(start 0.12065 -0.2794)
			(end 0.12065 -0.3048)
			(stroke
				(width 0.1)
				(type default)
			)
			(layer "F.Fab")
		)
		(fp_line
			(start 0.12065 -0.3048)
			(end 0.67945 -0.3048)
			(stroke
				(width 0.1)
				(type default)
			)
			(layer "F.Fab")
		)
		(fp_line
			(start 0.67945 -0.3048)
			(end 0.67945 0.3048)
			(stroke
				(width 0.1)
				(type default)
			)
			(layer "F.Fab")
		)
		(fp_line
			(start -0.67945 -0.305054)
			(end -0.12065 -0.305054)
			(stroke
				(width 0.1)
				(type default)
			)
			(layer "F.Fab")
		)
		(fp_line
			(start -0.12065 -0.305054)
			(end -0.12065 -0.2794)
			(stroke
				(width 0.1)
				(type default)
			)
			(layer "F.Fab")
		)
		(pad "1" smd circle
			(at -0.40005 0 270)
			(size 0 0)
			(layers "F.Cu" "F.Mask" "F.Paste")
			(net "SSD12_PWRDIS")
		)
		(pad "2" smd circle
			(at 0.40005 0 270)
			(size 0 0)
			(layers "F.Cu" "F.Mask" "F.Paste")
			(net "SSD12_PWRDIS_R")
		)
	)
	(footprint ""
		(layer "F.Cu")
		(at 356.349808 -158.828994 180)
		(property "Reference" "R5968"
			(at 0 0 180)
			(layer "F.SilkS")
			(hide yes)
			(effects
				(font
					(size 1.27 1.27)
				)
			)
		)
		(property "Value" ""
			(at 0 0 180)
			(layer "F.Fab")
			(effects
				(font
					(size 1.27 1.27)
				)
			)
		)
		(duplicate_pad_numbers_are_jumpers no)
		(fp_line
			(start 0.7874 0.4064)
			(end -0.7874 0.4064)
			(stroke
				(width 0.1524)
				(type default)
			)
			(layer "F.SilkS")
		)
		(fp_line
			(start 0.7874 -0.4064)
			(end 0.7874 0.4064)
			(stroke
				(width 0.1524)
				(type default)
			)
			(layer "F.SilkS")
		)
		(fp_line
			(start -0.7874 0.4064)
			(end -0.7874 -0.4064)
			(stroke
				(width 0.1524)
				(type default)
			)
			(layer "F.SilkS")
		)
		(fp_line
			(start -0.7874 -0.4064)
			(end 0.7874 -0.4064)
			(stroke
				(width 0.1524)
				(type default)
			)
			(layer "F.SilkS")
		)
		(fp_line
			(start 0.67945 0.3048)
			(end 0.120396 0.3048)
			(stroke
				(width 0.1)
				(type default)
			)
			(layer "F.Fab")
		)
		(fp_line
			(start 0.67945 -0.3048)
			(end 0.67945 0.3048)
			(stroke
				(width 0.1)
				(type default)
			)
			(layer "F.Fab")
		)
		(fp_line
			(start 0.12065 -0.2794)
			(end 0.12065 -0.3048)
			(stroke
				(width 0.1)
				(type default)
			)
			(layer "F.Fab")
		)
		(fp_line
			(start 0.12065 -0.3048)
			(end 0.67945 -0.3048)
			(stroke
				(width 0.1)
				(type default)
			)
			(layer "F.Fab")
		)
		(fp_line
			(start 0.120396 0.3048)
			(end 0.120396 0.2794)
			(stroke
				(width 0.1)
				(type default)
			)
			(layer "F.Fab")
		)
		(fp_line
			(start 0.120396 0.2794)
			(end -0.12065 0.2794)
			(stroke
				(width 0.1)
				(type default)
			)
			(layer "F.Fab")
		)
		(fp_line
			(start -0.12065 0.3048)
			(end -0.67945 0.3048)
			(stroke
				(width 0.1)
				(type default)
			)
			(layer "F.Fab")
		)
		(fp_line
			(start -0.12065 0.2794)
			(end -0.12065 0.3048)
			(stroke
				(width 0.1)
				(type default)
			)
			(layer "F.Fab")
		)
		(fp_line
			(start -0.12065 -0.2794)
			(end 0.12065 -0.2794)
			(stroke
				(width 0.1)
				(type default)
			)
			(layer "F.Fab")
		)
		(fp_line
			(start -0.12065 -0.305054)
			(end -0.12065 -0.2794)
			(stroke
				(width 0.1)
				(type default)
			)
			(layer "F.Fab")
		)
		(fp_line
			(start -0.67945 0.3048)
			(end -0.67945 -0.305054)
			(stroke
				(width 0.1)
				(type default)
			)
			(layer "F.Fab")
		)
		(fp_line
			(start -0.67945 -0.305054)
			(end -0.12065 -0.305054)
			(stroke
				(width 0.1)
				(type default)
			)
			(layer "F.Fab")
		)
		(pad "1" smd circle
			(at -0.40005 0 180)
			(size 0 0)
			(layers "F.Cu" "F.Mask" "F.Paste")
			(net "PWRGD_P12V_NIC6_CO")
		)
		(pad "2" smd circle
			(at 0.40005 0 180)
			(size 0 0)
			(layers "F.Cu" "F.Mask" "F.Paste")
			(net "PWRGD_P12V_NIC6_R")
		)
	)
)
